FILE_TYPE=LIBRARY_PARTS;
primitive 'GL852GOHY60';
  pin
    'X1':
      PIN_NUMBER='(10)';
      INPUT_LOAD='(-0.01,0.01)';
    'X2':
      PIN_NUMBER='(11)';
      OUTPUT_LOAD='(1.0,-1.0)';
    'TEST||SCL':
      PIN_NUMBER='(18)';
      BIDIRECTIONAL='TRUE';
      INPUT_LOAD='(-0.01,0.01)';
      OUTPUT_LOAD='(1.0,-1.0)';
    'SDA':
      PIN_NUMBER='(26)';
      BIDIRECTIONAL='TRUE';
      INPUT_LOAD='(-0.01,0.01)';
      OUTPUT_LOAD='(1.0,-1.0)';
    'V5':
      PIN_NUMBER='(27)';
      PINUSE='POWER';
      NO_LOAD_CHECK='Both';
      NO_IO_CHECK='Both';
      NO_ASSERT_CHECK='TRUE';
      NO_DIR_CHECK='TRUE';
      ALLOW_CONNECT='TRUE';
    'V33':
      PIN_NUMBER='(28)';
      PINUSE='POWER';
      NO_LOAD_CHECK='Both';
      NO_IO_CHECK='Both';
      NO_ASSERT_CHECK='TRUE';
      NO_DIR_CHECK='TRUE';
      ALLOW_CONNECT='TRUE';
    'AVDD'<0>:
      PIN_NUMBER='(5)';
      PINUSE='POWER';
      NO_LOAD_CHECK='Both';
      NO_IO_CHECK='Both';
      NO_ASSERT_CHECK='TRUE';
      NO_DIR_CHECK='TRUE';
      ALLOW_CONNECT='TRUE';
    'AVDD'<1>:
      PIN_NUMBER='(9)';
      PINUSE='POWER';
      NO_LOAD_CHECK='Both';
      NO_IO_CHECK='Both';
      NO_ASSERT_CHECK='TRUE';
      NO_DIR_CHECK='TRUE';
      ALLOW_CONNECT='TRUE';
    'AVDD'<2>:
      PIN_NUMBER='(14)';
      PINUSE='POWER';
      NO_LOAD_CHECK='Both';
      NO_IO_CHECK='Both';
      NO_ASSERT_CHECK='TRUE';
      NO_DIR_CHECK='TRUE';
      ALLOW_CONNECT='TRUE';
    'DVDD':
      PIN_NUMBER='(21)';
      PINUSE='POWER';
      NO_LOAD_CHECK='Both';
      NO_IO_CHECK='Both';
      NO_ASSERT_CHECK='TRUE';
      NO_DIR_CHECK='TRUE';
      ALLOW_CONNECT='TRUE';
    'TH':
      PIN_NUMBER='(TH)';
      PINUSE='POWER';
      NO_LOAD_CHECK='Both';
      NO_IO_CHECK='Both';
      NO_ASSERT_CHECK='TRUE';
      NO_DIR_CHECK='TRUE';
      ALLOW_CONNECT='TRUE';
    'OVCUR1#||SMC':
      PIN_NUMBER='(25)';
      INPUT_LOAD='(-0.01,0.01)';
    'OVCUR2#||SMD':
      PIN_NUMBER='(24)';
      BIDIRECTIONAL='TRUE';
      INPUT_LOAD='(-0.01,0.01)';
      OUTPUT_LOAD='(1.0,-1.0)';
    'OVCUR3#':
      PIN_NUMBER='(20)';
      INPUT_LOAD='(-0.01,0.01)';
    'OVCUR4#':
      PIN_NUMBER='(19)';
      INPUT_LOAD='(-0.01,0.01)';
    'RESET#':
      PIN_NUMBER='(17)';
      INPUT_LOAD='(-0.01,0.01)';
    'PGANG':
      PIN_NUMBER='(23)';
      BIDIRECTIONAL='TRUE';
      INPUT_LOAD='(-0.01,0.01)';
      OUTPUT_LOAD='(1.0,-1.0)';
    'PSELF':
      PIN_NUMBER='(22)';
      INPUT_LOAD='(-0.01,0.01)';
    'RREF':
      PIN_NUMBER='(8)';
      INPUT_LOAD='(-0.01,0.01)';
    'DP0':
      PIN_NUMBER='(2)';
      BIDIRECTIONAL='TRUE';
      INPUT_LOAD='(-0.01,0.01)';
      OUTPUT_LOAD='(1.0,-1.0)';
    'DM0':
      PIN_NUMBER='(1)';
      BIDIRECTIONAL='TRUE';
      INPUT_LOAD='(-0.01,0.01)';
      OUTPUT_LOAD='(1.0,-1.0)';
    'DP1':
      PIN_NUMBER='(4)';
      BIDIRECTIONAL='TRUE';
      INPUT_LOAD='(-0.01,0.01)';
      OUTPUT_LOAD='(1.0,-1.0)';
    'DM1':
      PIN_NUMBER='(3)';
      BIDIRECTIONAL='TRUE';
      INPUT_LOAD='(-0.01,0.01)';
      OUTPUT_LOAD='(1.0,-1.0)';
    'DP2':
      PIN_NUMBER='(7)';
      BIDIRECTIONAL='TRUE';
      INPUT_LOAD='(-0.01,0.01)';
      OUTPUT_LOAD='(1.0,-1.0)';
    'DM2':
      PIN_NUMBER='(6)';
      BIDIRECTIONAL='TRUE';
      INPUT_LOAD='(-0.01,0.01)';
      OUTPUT_LOAD='(1.0,-1.0)';
    'DP3':
      PIN_NUMBER='(13)';
      BIDIRECTIONAL='TRUE';
      INPUT_LOAD='(-0.01,0.01)';
      OUTPUT_LOAD='(1.0,-1.0)';
    'DM3':
      PIN_NUMBER='(12)';
      BIDIRECTIONAL='TRUE';
      INPUT_LOAD='(-0.01,0.01)';
      OUTPUT_LOAD='(1.0,-1.0)';
    'DP4':
      PIN_NUMBER='(16)';
      BIDIRECTIONAL='TRUE';
      INPUT_LOAD='(-0.01,0.01)';
      OUTPUT_LOAD='(1.0,-1.0)';
    'DM4':
      PIN_NUMBER='(15)';
      BIDIRECTIONAL='TRUE';
      INPUT_LOAD='(-0.01,0.01)';
      OUTPUT_LOAD='(1.0,-1.0)';
  end_pin;
  body
    PART_NAME='GL852GOHY60';
    BODY_NAME='GL852GOHY60';
    PHYS_DES_PREFIX='U';
    CLASS='IC';
  end_body;
end_primitive;

END.
